# S9S_MB_2U (Grand Teton) — schematic netlist excerpt (pin names and nets, part order shuffled) for the footprints in the layout excerpt that follows; sources: Cadence DE-HDL packaged netlist, KiCad conversion of 03242023_DA0F0TMBIJ0_F0T_Motherboard_J_brd_V01_OCP.brd

R1369  Q_RES  1K 1% CHIP  pkg 0402LF  page 239 : A = PD_JTAG_DBP_B0 ; B = GND
PC1264  Q_CAP  0.1UF 25V 10% X7R  pkg 0402  page 299 : A = PVPP_HBM_CPU1_REF ; B = SH_PVPP_HBM_CPU1_N

(kicad_pcb
	(version 20260206)
	(generator "pcbnew")
	(generator_version "10.0")
	(general
		(thickness 1.6)
		(legacy_teardrops no)
	)
	(paper "A4")
	(title_block
		(title "03242023_DA0F0TMBIJ0_F0T_Motherboard_J_brd_V01_OCP.brd")
		(comment 1 "Grand Teton / footprints 1960-1962 of 6105")
	)
	(layers
		(0 "F.Cu" signal "TOP")
		(4 "In1.Cu" signal "GND")
		(6 "In2.Cu" signal "IN1")
		(8 "In3.Cu" signal "GND1")
		(10 "In4.Cu" signal "IN2")
		(12 "In5.Cu" signal "GND2")
		(14 "In6.Cu" signal "IN3")
		(16 "In7.Cu" signal "GND3")
		(18 "In8.Cu" signal "VCC")
		(20 "In9.Cu" signal "VCC1")
		(22 "In10.Cu" signal "GND4")
		(24 "In11.Cu" signal "IN4")
		(26 "In12.Cu" signal "GND5")
		(28 "In13.Cu" signal "IN5")
		(30 "In14.Cu" signal "GND6")
		(32 "In15.Cu" signal "IN6")
		(34 "In16.Cu" signal "GND7")
		(2 "B.Cu" signal "BOTTOM")
		(9 "F.Adhes" user "F.Adhesive")
		(11 "B.Adhes" user "B.Adhesive")
		(13 "F.Paste" user "Package Geometry/Pastemask Top")
		(15 "B.Paste" user "Package Geometry/Pastemask Bottom")
		(5 "F.SilkS" user "Ref Des/Silkscreen Top")
		(7 "B.SilkS" user "Ref Des/Silkscreen Bottom")
		(1 "F.Mask" user "Board Geometry/Soldermask Top")
		(3 "B.Mask" user "Board Geometry/Soldermask Bottom")
		(17 "Dwgs.User" user "User.Drawings")
		(19 "Cmts.User" user "User.Comments")
		(21 "Eco1.User" user "User.Eco1")
		(23 "Eco2.User" user "User.Eco2")
		(25 "Edge.Cuts" user "Board Geometry/Outline")
		(27 "Margin" user)
		(31 "F.CrtYd" user "Package Geometry/Place Bound Top")
		(29 "B.CrtYd" user "Package Geometry/Place Bound Bottom")
		(35 "F.Fab" user "Ref Des/Assembly Top")
		(33 "B.Fab" user "Ref Des/Assembly Bottom")
	)
	(footprint ""
		(layer "F.Cu")
		(at 379.319536 -105.483152 90)
		(property "Reference" "R1369"
			(at 0 0 90)
			(layer "F.SilkS")
			(hide yes)
			(effects
				(font
					(size 1.27 1.27)
				)
			)
		)
		(property "Value" ""
			(at 0 0 90)
			(layer "F.Fab")
			(effects
				(font
					(size 1.27 1.27)
				)
			)
		)
		(duplicate_pad_numbers_are_jumpers no)
		(fp_line
			(start 0.7874 -0.4064)
			(end 0.7874 0.4064)
			(stroke
				(width 0.1524)
				(type default)
			)
			(layer "F.SilkS")
		)
		(fp_line
			(start -0.7874 -0.4064)
			(end 0.7874 -0.4064)
			(stroke
				(width 0.1524)
				(type default)
			)
			(layer "F.SilkS")
		)
		(fp_line
			(start 0.7874 0.4064)
			(end -0.7874 0.4064)
			(stroke
				(width 0.1524)
				(type default)
			)
			(layer "F.SilkS")
		)
		(fp_line
			(start -0.7874 0.4064)
			(end -0.7874 -0.4064)
			(stroke
				(width 0.1524)
				(type default)
			)
			(layer "F.SilkS")
		)
		(fp_line
			(start -0.12065 -0.305054)
			(end -0.12065 -0.2794)
			(stroke
				(width 0.1)
				(type default)
			)
			(layer "F.Fab")
		)
		(fp_line
			(start -0.67945 -0.305054)
			(end -0.12065 -0.305054)
			(stroke
				(width 0.1)
				(type default)
			)
			(layer "F.Fab")
		)
		(fp_line
			(start 0.67945 -0.3048)
			(end 0.67945 0.3048)
			(stroke
				(width 0.1)
				(type default)
			)
			(layer "F.Fab")
		)
		(fp_line
			(start 0.12065 -0.3048)
			(end 0.67945 -0.3048)
			(stroke
				(width 0.1)
				(type default)
			)
			(layer "F.Fab")
		)
		(fp_line
			(start 0.12065 -0.2794)
			(end 0.12065 -0.3048)
			(stroke
				(width 0.1)
				(type default)
			)
			(layer "F.Fab")
		)
		(fp_line
			(start -0.12065 -0.2794)
			(end 0.12065 -0.2794)
			(stroke
				(width 0.1)
				(type default)
			)
			(layer "F.Fab")
		)
		(fp_line
			(start 0.120396 0.2794)
			(end -0.12065 0.2794)
			(stroke
				(width 0.1)
				(type default)
			)
			(layer "F.Fab")
		)
		(fp_line
			(start -0.12065 0.2794)
			(end -0.12065 0.3048)
			(stroke
				(width 0.1)
				(type default)
			)
			(layer "F.Fab")
		)
		(fp_line
			(start 0.67945 0.3048)
			(end 0.120396 0.3048)
			(stroke
				(width 0.1)
				(type default)
			)
			(layer "F.Fab")
		)
		(fp_line
			(start 0.120396 0.3048)
			(end 0.120396 0.2794)
			(stroke
				(width 0.1)
				(type default)
			)
			(layer "F.Fab")
		)
		(fp_line
			(start -0.12065 0.3048)
			(end -0.67945 0.3048)
			(stroke
				(width 0.1)
				(type default)
			)
			(layer "F.Fab")
		)
		(fp_line
			(start -0.67945 0.3048)
			(end -0.67945 -0.305054)
			(stroke
				(width 0.1)
				(type default)
			)
			(layer "F.Fab")
		)
		(pad "1" smd circle
			(at -0.40005 0 90)
			(size 0 0)
			(layers "F.Cu" "F.Mask" "F.Paste")
			(net "PD_JTAG_DBP_B0")
		)
		(pad "2" smd circle
			(at 0.40005 0 90)
			(size 0 0)
			(layers "F.Cu" "F.Mask" "F.Paste")
			(net "GND")
		)
	)
	(footprint ""
		(layer "F.Cu")
		(at 459.22946 -420.632128)
		(property "Reference" ""
			(at 0 0 0)
			(layer "F.SilkS")
			(hide yes)
			(effects
				(font
					(size 1.27 1.27)
				)
			)
		)
		(property "Value" ""
			(at 0 0 0)
			(layer "F.Fab")
			(effects
				(font
					(size 1.27 1.27)
				)
			)
		)
		(duplicate_pad_numbers_are_jumpers no)
		(pad "1" smd circle
			(at 0 0)
			(size 0.9906 0.9906)
			(layers "F.Cu" "F.Mask" "F.Paste")
			(net "Net_285")
		)
		(zone
			(layer "F.Cu")
			(hatch none 0.5)
			(connect_pads
				(clearance 0)
			)
			(min_thickness 0.25)
			(keepout
				(tracks not_allowed)
				(vias allowed)
				(pads allowed)
				(copperpour not_allowed)
				(footprints allowed)
			)
			(placement
				(enabled no)
				(sheetname "")
			)
			(fill
				(thermal_gap 0.5)
				(thermal_bridge_width 0.5)
				(island_removal_mode 0)
			)
			(polygon
				(pts
					(arc
						(start 460.85506 -420.632128)
						(mid 457.60386 -420.632128)
						(end 460.85506 -420.632128)
					)
				)
			)
		)
	)
	(footprint ""
		(layer "F.Cu")
		(at 121.430034 -358.430576)
		(property "Reference" "PC1264"
			(at 0 0 0)
			(layer "F.SilkS")
			(hide yes)
			(effects
				(font
					(size 1.27 1.27)
				)
			)
		)
		(property "Value" ""
			(at 0 0 0)
			(layer "F.Fab")
			(effects
				(font
					(size 1.27 1.27)
				)
			)
		)
		(duplicate_pad_numbers_are_jumpers no)
		(fp_line
			(start -0.7874 -0.4064)
			(end 0.7874 -0.4064)
			(stroke
				(width 0.1524)
				(type default)
			)
			(layer "F.SilkS")
		)
		(fp_line
			(start -0.7874 0.4064)
			(end -0.7874 -0.4064)
			(stroke
				(width 0.1524)
				(type default)
			)
			(layer "F.SilkS")
		)
		(fp_line
			(start 0.7874 -0.4064)
			(end 0.7874 0.4064)
			(stroke
				(width 0.1524)
				(type default)
			)
			(layer "F.SilkS")
		)
		(fp_line
			(start 0.7874 0.4064)
			(end -0.7874 0.4064)
			(stroke
				(width 0.1524)
				(type default)
			)
			(layer "F.SilkS")
		)
		(fp_line
			(start -0.67945 -0.305054)
			(end -0.12065 -0.305054)
			(stroke
				(width 0.1)
				(type default)
			)
			(layer "F.Fab")
		)
		(fp_line
			(start -0.67945 0.3048)
			(end -0.67945 -0.305054)
			(stroke
				(width 0.1)
				(type default)
			)
			(layer "F.Fab")
		)
		(fp_line
			(start -0.12065 -0.305054)
			(end -0.12065 -0.2794)
			(stroke
				(width 0.1)
				(type default)
			)
			(layer "F.Fab")
		)
		(fp_line
			(start -0.12065 -0.2794)
			(end 0.12065 -0.2794)
			(stroke
				(width 0.1)
				(type default)
			)
			(layer "F.Fab")
		)
		(fp_line
			(start -0.12065 0.2794)
			(end -0.12065 0.3048)
			(stroke
				(width 0.1)
				(type default)
			)
			(layer "F.Fab")
		)
		(fp_line
			(start -0.12065 0.3048)
			(end -0.67945 0.3048)
			(stroke
				(width 0.1)
				(type default)
			)
			(layer "F.Fab")
		)
		(fp_line
			(start 0.120396 0.2794)
			(end -0.12065 0.2794)
			(stroke
				(width 0.1)
				(type default)
			)
			(layer "F.Fab")
		)
		(fp_line
			(start 0.120396 0.3048)
			(end 0.120396 0.2794)
			(stroke
				(width 0.1)
				(type default)
			)
			(layer "F.Fab")
		)
		(fp_line
			(start 0.12065 -0.3048)
			(end 0.67945 -0.3048)
			(stroke
				(width 0.1)
				(type default)
			)
			(layer "F.Fab")
		)
		(fp_line
			(start 0.12065 -0.2794)
			(end 0.12065 -0.3048)
			(stroke
				(width 0.1)
				(type default)
			)
			(layer "F.Fab")
		)
		(fp_line
			(start 0.67945 -0.3048)
			(end 0.67945 0.3048)
			(stroke
				(width 0.1)
				(type default)
			)
			(layer "F.Fab")
		)
		(fp_line
			(start 0.67945 0.3048)
			(end 0.120396 0.3048)
			(stroke
				(width 0.1)
				(type default)
			)
			(layer "F.Fab")
		)
		(pad "1" smd circle
			(at -0.40005 0)
			(size 0 0)
			(layers "F.Cu" "F.Mask" "F.Paste")
			(net "PVPP_HBM_CPU1_REF")
		)
		(pad "2" smd circle
			(at 0.40005 0)
			(size 0 0)
			(layers "F.Cu" "F.Mask" "F.Paste")
			(net "SH_PVPP_HBM_CPU1_N")
		)
	)
)
